(kicad_pcb
	(version 20260206)
	(generator "pcbnew")
	(generator_version "10.0")
	(general
		(thickness 1.6)
		(legacy_teardrops no)
	)
	(paper "A4")
	(title_block
		(title "Wiwynn_Tioga_Pass_MB.brd")
		(comment 1 "Tioga Pass / footprints 3448-3454 of 4770")
	)
	(layers
		(0 "F.Cu" signal "TOP")
		(4 "In1.Cu" signal "L2GND")
		(6 "In2.Cu" signal "L3")
		(8 "In3.Cu" signal "L4GND")
		(10 "In4.Cu" signal "L5")
		(12 "In5.Cu" signal "L6GND")
		(14 "In6.Cu" signal "L7VCC")
		(16 "In7.Cu" signal "L8VCC")
		(18 "In8.Cu" signal "L9GND")
		(20 "In9.Cu" signal "L10")
		(22 "In10.Cu" signal "L11GND")
		(24 "In11.Cu" signal "L12")
		(26 "In12.Cu" signal "L13GND")
		(2 "B.Cu" signal "BOTTOM")
		(9 "F.Adhes" user "F.Adhesive")
		(11 "B.Adhes" user "B.Adhesive")
		(13 "F.Paste" user "Package Geometry/Pastemask Top")
		(15 "B.Paste" user "Package Geometry/Pastemask Bottom")
		(5 "F.SilkS" user "Ref Des/Silkscreen Top")
		(7 "B.SilkS" user "Ref Des/Silkscreen Bottom")
		(1 "F.Mask" user "Board Geometry/Soldermask Top")
		(3 "B.Mask" user "Board Geometry/Soldermask Bottom")
		(17 "Dwgs.User" user "User.Drawings")
		(19 "Cmts.User" user "User.Comments")
		(21 "Eco1.User" user "User.Eco1")
		(23 "Eco2.User" user "User.Eco2")
		(25 "Edge.Cuts" user "Board Geometry/Outline")
		(27 "Margin" user)
		(31 "F.CrtYd" user "Package Geometry/Place Bound Top")
		(29 "B.CrtYd" user "Package Geometry/Place Bound Bottom")
		(35 "F.Fab" user "Ref Des/Assembly Top")
		(33 "B.Fab" user "Ref Des/Assembly Bottom")
	)
	(footprint ""
		(layer "B.Cu")
		(at 348.600014 -122.459242 -90)
		(property "Reference" "R771"
			(at 0.8382 -0.67818 270)
			(unlocked yes)
			(layer "B.SilkS")
			(effects
				(font
					(size 0.4064 0.254)
					(thickness 0.1524)
				)
				(justify left mirror)
			)
		)
		(property "Value" ""
			(at 0 0 90)
			(layer "B.Fab")
			(effects
				(font
					(size 1.27 1.27)
				)
				(justify mirror)
			)
		)
		(duplicate_pad_numbers_are_jumpers no)
		(fp_poly
			(pts
				(xy 0.2794 -0.1016) (xy -0.2794 -0.1016) (xy -0.2794 0.9906) (xy 0.2794 0.9906)
			)
			(stroke
				(width 0)
				(type default)
			)
			(fill no)
			(layer "B.CrtYd")
		)
		(fp_line
			(start -0.2794 0.9906)
			(end -0.2794 -0.1016)
			(stroke
				(width 0.1)
				(type default)
			)
			(layer "B.Fab")
		)
		(fp_line
			(start 0.2794 0.9906)
			(end -0.2794 0.9906)
			(stroke
				(width 0.1)
				(type default)
			)
			(layer "B.Fab")
		)
		(fp_line
			(start -0.2794 -0.1016)
			(end 0.2794 -0.1016)
			(stroke
				(width 0.1)
				(type default)
			)
			(layer "B.Fab")
		)
		(fp_line
			(start 0.2794 -0.1016)
			(end 0.2794 0.9906)
			(stroke
				(width 0.1)
				(type default)
			)
			(layer "B.Fab")
		)
		(pad "1" smd rect
			(at 0 0 90)
			(size 0.508 0.508)
			(layers "B.Cu" "B.Mask" "B.Paste")
			(net "P3E_CPU0_PE1_PCH_RXN<13>")
		)
		(pad "2" smd rect
			(at 0 0.889 90)
			(size 0.508 0.508)
			(layers "B.Cu" "B.Mask" "B.Paste")
			(net "P3E_CPU0_PE1_PCH_CON_RXN<13>")
		)
		(zone
			(layer "B.Cu")
			(hatch none 0.5)
			(connect_pads
				(clearance 0)
			)
			(min_thickness 0.25)
			(keepout
				(tracks not_allowed)
				(vias allowed)
				(pads allowed)
				(copperpour not_allowed)
				(footprints allowed)
			)
			(placement
				(enabled no)
				(sheetname "")
			)
			(fill
				(thermal_gap 0.5)
				(thermal_bridge_width 0.5)
				(island_removal_mode 0)
			)
			(polygon
				(pts
					(xy 347.965014 -122.205242) (xy 347.965014 -122.713242) (xy 348.346014 -122.713242) (xy 348.346014 -122.205242)
				)
			)
		)
		(zone
			(layer "B.Cu")
			(hatch none 0.5)
			(connect_pads
				(clearance 0)
			)
			(min_thickness 0.25)
			(keepout
				(tracks allowed)
				(vias not_allowed)
				(pads allowed)
				(copperpour not_allowed)
				(footprints allowed)
			)
			(placement
				(enabled no)
				(sheetname "")
			)
			(fill
				(thermal_gap 0.5)
				(thermal_bridge_width 0.5)
				(island_removal_mode 0)
			)
			(polygon
				(pts
					(xy 348.346014 -122.205242) (xy 348.346014 -122.713242) (xy 347.965014 -122.713242) (xy 347.965014 -122.205242)
				)
			)
		)
	)
	(footprint ""
		(layer "B.Cu")
		(at 3.04292 -5.41782 90)
		(property "Reference" "R9U1"
			(at 0 0 90)
			(layer "B.SilkS")
			(hide yes)
			(effects
				(font
					(size 1.27 1.27)
				)
				(justify mirror)
			)
		)
		(property "Value" ""
			(at 0 0 90)
			(layer "B.Fab")
			(effects
				(font
					(size 1.27 1.27)
				)
				(justify mirror)
			)
		)
		(duplicate_pad_numbers_are_jumpers no)
		(fp_rect
			(start -0.2794 -0.1016)
			(end 0.2794 0.9906)
			(stroke
				(width 0)
				(type default)
			)
			(fill no)
			(layer "B.CrtYd")
		)
		(fp_line
			(start 0.2794 -0.1016)
			(end 0.2794 0.9906)
			(stroke
				(width 0.1)
				(type default)
			)
			(layer "B.Fab")
		)
		(fp_line
			(start -0.2794 -0.1016)
			(end 0.2794 -0.1016)
			(stroke
				(width 0.1)
				(type default)
			)
			(layer "B.Fab")
		)
		(fp_line
			(start 0.2794 0.9906)
			(end -0.2794 0.9906)
			(stroke
				(width 0.1)
				(type default)
			)
			(layer "B.Fab")
		)
		(fp_line
			(start -0.2794 0.9906)
			(end -0.2794 -0.1016)
			(stroke
				(width 0.1)
				(type default)
			)
			(layer "B.Fab")
		)
		(pad "1" smd rect
			(at 0 0 270)
			(size 0.508 0.508)
			(layers "B.Cu" "B.Mask" "B.Paste")
			(net "VR_PVDDQ_GHJ_PH1_VCIN")
		)
		(pad "2" smd rect
			(at 0 0.889 270)
			(size 0.508 0.508)
			(layers "B.Cu" "B.Mask" "B.Paste")
			(net "P5V_STBY")
		)
		(zone
			(layer "B.Cu")
			(hatch none 0.5)
			(connect_pads
				(clearance 0)
			)
			(min_thickness 0.25)
			(keepout
				(tracks allowed)
				(vias not_allowed)
				(pads allowed)
				(copperpour not_allowed)
				(footprints allowed)
			)
			(placement
				(enabled no)
				(sheetname "")
			)
			(fill
				(thermal_gap 0.5)
				(thermal_bridge_width 0.5)
				(island_removal_mode 0)
			)
			(polygon
				(pts
					(xy 3.29692 -5.16382) (xy 3.67792 -5.16382) (xy 3.67792 -5.67182) (xy 3.29692 -5.67182)
				)
			)
		)
		(zone
			(layer "B.Cu")
			(hatch none 0.5)
			(connect_pads
				(clearance 0)
			)
			(min_thickness 0.25)
			(keepout
				(tracks not_allowed)
				(vias allowed)
				(pads allowed)
				(copperpour not_allowed)
				(footprints allowed)
			)
			(placement
				(enabled no)
				(sheetname "")
			)
			(fill
				(thermal_gap 0.5)
				(thermal_bridge_width 0.5)
				(island_removal_mode 0)
			)
			(polygon
				(pts
					(xy 3.29692 -5.16382) (xy 3.67792 -5.16382) (xy 3.67792 -5.67182) (xy 3.29692 -5.67182)
				)
			)
		)
	)
	(footprint ""
		(layer "B.Cu")
		(at 487.1085 -151.6126 90)
		(property "Reference" "R1L6"
			(at 0 0 90)
			(layer "B.SilkS")
			(hide yes)
			(effects
				(font
					(size 1.27 1.27)
				)
				(justify mirror)
			)
		)
		(property "Value" ""
			(at 0 0 90)
			(layer "B.Fab")
			(effects
				(font
					(size 1.27 1.27)
				)
				(justify mirror)
			)
		)
		(duplicate_pad_numbers_are_jumpers no)
		(fp_poly
			(pts
				(xy 0.2794 -0.1016) (xy -0.2794 -0.1016) (xy -0.2794 0.9906) (xy 0.2794 0.9906)
			)
			(stroke
				(width 0)
				(type default)
			)
			(fill no)
			(layer "B.CrtYd")
		)
		(fp_line
			(start 0.2794 -0.1016)
			(end 0.2794 0.9906)
			(stroke
				(width 0.1)
				(type default)
			)
			(layer "B.Fab")
		)
		(fp_line
			(start -0.2794 -0.1016)
			(end 0.2794 -0.1016)
			(stroke
				(width 0.1)
				(type default)
			)
			(layer "B.Fab")
		)
		(fp_line
			(start 0.2794 0.9906)
			(end -0.2794 0.9906)
			(stroke
				(width 0.1)
				(type default)
			)
			(layer "B.Fab")
		)
		(fp_line
			(start -0.2794 0.9906)
			(end -0.2794 -0.1016)
			(stroke
				(width 0.1)
				(type default)
			)
			(layer "B.Fab")
		)
		(pad "1" smd rect
			(at 0 0 270)
			(size 0.508 0.508)
			(layers "B.Cu" "B.Mask" "B.Paste")
			(net "FM_UART_SWITCH_N")
		)
		(pad "2" smd rect
			(at 0 0.889 270)
			(size 0.508 0.508)
			(layers "B.Cu" "B.Mask" "B.Paste")
			(net "FM_DB_UART_SEL0_N")
		)
		(zone
			(layer "B.Cu")
			(hatch none 0.5)
			(connect_pads
				(clearance 0)
			)
			(min_thickness 0.25)
			(keepout
				(tracks allowed)
				(vias not_allowed)
				(pads allowed)
				(copperpour not_allowed)
				(footprints allowed)
			)
			(placement
				(enabled no)
				(sheetname "")
			)
			(fill
				(thermal_gap 0.5)
				(thermal_bridge_width 0.5)
				(island_removal_mode 0)
			)
			(polygon
				(pts
					(xy 487.3625 -151.8666) (xy 487.3625 -151.3586) (xy 487.7435 -151.3586) (xy 487.7435 -151.8666)
				)
			)
		)
		(zone
			(layer "B.Cu")
			(hatch none 0.5)
			(connect_pads
				(clearance 0)
			)
			(min_thickness 0.25)
			(keepout
				(tracks not_allowed)
				(vias allowed)
				(pads allowed)
				(copperpour not_allowed)
				(footprints allowed)
			)
			(placement
				(enabled no)
				(sheetname "")
			)
			(fill
				(thermal_gap 0.5)
				(thermal_bridge_width 0.5)
				(island_removal_mode 0)
			)
			(polygon
				(pts
					(xy 487.7435 -151.8666) (xy 487.7435 -151.3586) (xy 487.3625 -151.3586) (xy 487.3625 -151.8666)
				)
			)
		)
	)
	(footprint ""
		(layer "B.Cu")
		(at 380.746 -87.3125 180)
		(property "Reference" "R7C13"
			(at 0 0 0)
			(layer "B.SilkS")
			(hide yes)
			(effects
				(font
					(size 1.27 1.27)
				)
				(justify mirror)
			)
		)
		(property "Value" ""
			(at 0 0 0)
			(layer "B.Fab")
			(effects
				(font
					(size 1.27 1.27)
				)
				(justify mirror)
			)
		)
		(duplicate_pad_numbers_are_jumpers no)
		(fp_poly
			(pts
				(xy 0.2794 -0.1016) (xy -0.2794 -0.1016) (xy -0.2794 0.9906) (xy 0.2794 0.9906)
			)
			(stroke
				(width 0)
				(type default)
			)
			(fill no)
			(layer "B.CrtYd")
		)
		(fp_line
			(start 0.2794 0.9906)
			(end -0.2794 0.9906)
			(stroke
				(width 0.1)
				(type default)
			)
			(layer "B.Fab")
		)
		(fp_line
			(start 0.2794 -0.1016)
			(end 0.2794 0.9906)
			(stroke
				(width 0.1)
				(type default)
			)
			(layer "B.Fab")
		)
		(fp_line
			(start -0.2794 0.9906)
			(end -0.2794 -0.1016)
			(stroke
				(width 0.1)
				(type default)
			)
			(layer "B.Fab")
		)
		(fp_line
			(start -0.2794 -0.1016)
			(end 0.2794 -0.1016)
			(stroke
				(width 0.1)
				(type default)
			)
			(layer "B.Fab")
		)
		(pad "1" smd rect
			(at 0 0)
			(size 0.508 0.508)
			(layers "B.Cu" "B.Mask" "B.Paste")
			(net "P3V3_STBY")
		)
		(pad "2" smd rect
			(at 0 0.889)
			(size 0.508 0.508)
			(layers "B.Cu" "B.Mask" "B.Paste")
			(net "FM_UART_PRES_N")
		)
		(zone
			(layer "B.Cu")
			(hatch none 0.5)
			(connect_pads
				(clearance 0)
			)
			(min_thickness 0.25)
			(keepout
				(tracks not_allowed)
				(vias allowed)
				(pads allowed)
				(copperpour not_allowed)
				(footprints allowed)
			)
			(placement
				(enabled no)
				(sheetname "")
			)
			(fill
				(thermal_gap 0.5)
				(thermal_bridge_width 0.5)
				(island_removal_mode 0)
			)
			(polygon
				(pts
					(xy 380.492 -87.9475) (xy 381 -87.9475) (xy 381 -87.5665) (xy 380.492 -87.5665)
				)
			)
		)
		(zone
			(layer "B.Cu")
			(hatch none 0.5)
			(connect_pads
				(clearance 0)
			)
			(min_thickness 0.25)
			(keepout
				(tracks allowed)
				(vias not_allowed)
				(pads allowed)
				(copperpour not_allowed)
				(footprints allowed)
			)
			(placement
				(enabled no)
				(sheetname "")
			)
			(fill
				(thermal_gap 0.5)
				(thermal_bridge_width 0.5)
				(island_removal_mode 0)
			)
			(polygon
				(pts
					(xy 380.492 -87.5665) (xy 381 -87.5665) (xy 381 -87.9475) (xy 380.492 -87.9475)
				)
			)
		)
	)
	(footprint ""
		(layer "B.Cu")
		(at 1.3462 -137.795 90)
		(property "Reference" "C9L10"
			(at 0 0 90)
			(layer "B.SilkS")
			(hide yes)
			(effects
				(font
					(size 1.27 1.27)
				)
				(justify mirror)
			)
		)
		(property "Value" ""
			(at 0 0 90)
			(layer "B.Fab")
			(effects
				(font
					(size 1.27 1.27)
				)
				(justify mirror)
			)
		)
		(duplicate_pad_numbers_are_jumpers no)
		(fp_rect
			(start -0.7239 -0.2159)
			(end 0.7239 1.9939)
			(stroke
				(width 0)
				(type default)
			)
			(fill no)
			(layer "B.CrtYd")
		)
		(fp_line
			(start 0.7239 -0.2159)
			(end 0.7239 1.9939)
			(stroke
				(width 0.1)
				(type default)
			)
			(layer "B.Fab")
		)
		(fp_line
			(start -0.7239 -0.2159)
			(end 0.7239 -0.2159)
			(stroke
				(width 0.1)
				(type default)
			)
			(layer "B.Fab")
		)
		(fp_line
			(start 0.7239 1.9939)
			(end -0.7239 1.9939)
			(stroke
				(width 0.1)
				(type default)
			)
			(layer "B.Fab")
		)
		(fp_line
			(start -0.7239 1.9939)
			(end -0.7239 -0.2159)
			(stroke
				(width 0.1)
				(type default)
			)
			(layer "B.Fab")
		)
		(pad "1" smd rect
			(at 0 0 270)
			(size 1.27 1.016)
			(layers "B.Cu" "B.Mask" "B.Paste")
			(net "VR_FET_SW_P12V_STBY_PVDDQ_KLM")
		)
		(pad "2" smd rect
			(at 0 1.778 270)
			(size 1.27 1.016)
			(layers "B.Cu" "B.Mask" "B.Paste")
			(net "GND")
		)
		(zone
			(layer "B.Cu")
			(hatch none 0.5)
			(connect_pads
				(clearance 0)
			)
			(min_thickness 0.25)
			(keepout
				(tracks not_allowed)
				(vias allowed)
				(pads allowed)
				(copperpour not_allowed)
				(footprints allowed)
			)
			(placement
				(enabled no)
				(sheetname "")
			)
			(fill
				(thermal_gap 0.5)
				(thermal_bridge_width 0.5)
				(island_removal_mode 0)
			)
			(polygon
				(pts
					(xy 1.8542 -137.16) (xy 2.6162 -137.16) (xy 2.6162 -138.43) (xy 1.8542 -138.43)
				)
			)
		)
	)
	(footprint ""
		(layer "B.Cu")
		(at 401.04568 -48.49368 -90)
		(property "Reference" "R3T5"
			(at 0.8382 -0.67818 270)
			(unlocked yes)
			(layer "B.SilkS")
			(effects
				(font
					(size 0.4064 0.254)
					(thickness 0.1524)
				)
				(justify left mirror)
			)
		)
		(property "Value" ""
			(at 0 0 90)
			(layer "B.Fab")
			(effects
				(font
					(size 1.27 1.27)
				)
				(justify mirror)
			)
		)
		(duplicate_pad_numbers_are_jumpers no)
		(fp_poly
			(pts
				(xy 0.2794 -0.1016) (xy -0.2794 -0.1016) (xy -0.2794 0.9906) (xy 0.2794 0.9906)
			)
			(stroke
				(width 0)
				(type default)
			)
			(fill no)
			(layer "B.CrtYd")
		)
		(fp_line
			(start -0.2794 0.9906)
			(end -0.2794 -0.1016)
			(stroke
				(width 0.1)
				(type default)
			)
			(layer "B.Fab")
		)
		(fp_line
			(start 0.2794 0.9906)
			(end -0.2794 0.9906)
			(stroke
				(width 0.1)
				(type default)
			)
			(layer "B.Fab")
		)
		(fp_line
			(start -0.2794 -0.1016)
			(end 0.2794 -0.1016)
			(stroke
				(width 0.1)
				(type default)
			)
			(layer "B.Fab")
		)
		(fp_line
			(start 0.2794 -0.1016)
			(end 0.2794 0.9906)
			(stroke
				(width 0.1)
				(type default)
			)
			(layer "B.Fab")
		)
		(pad "1" smd rect
			(at 0 0 90)
			(size 0.508 0.508)
			(layers "B.Cu" "B.Mask" "B.Paste")
			(net "P3V3_STBY")
		)
		(pad "2" smd rect
			(at 0 0.889 90)
			(size 0.508 0.508)
			(layers "B.Cu" "B.Mask" "B.Paste")
			(net "SPI_CS0_SECONDARY_R_N")
		)
		(zone
			(layer "B.Cu")
			(hatch none 0.5)
			(connect_pads
				(clearance 0)
			)
			(min_thickness 0.25)
			(keepout
				(tracks not_allowed)
				(vias allowed)
				(pads allowed)
				(copperpour not_allowed)
				(footprints allowed)
			)
			(placement
				(enabled no)
				(sheetname "")
			)
			(fill
				(thermal_gap 0.5)
				(thermal_bridge_width 0.5)
				(island_removal_mode 0)
			)
			(polygon
				(pts
					(xy 400.41068 -48.23968) (xy 400.41068 -48.74768) (xy 400.79168 -48.74768) (xy 400.79168 -48.23968)
				)
			)
		)
		(zone
			(layer "B.Cu")
			(hatch none 0.5)
			(connect_pads
				(clearance 0)
			)
			(min_thickness 0.25)
			(keepout
				(tracks allowed)
				(vias not_allowed)
				(pads allowed)
				(copperpour not_allowed)
				(footprints allowed)
			)
			(placement
				(enabled no)
				(sheetname "")
			)
			(fill
				(thermal_gap 0.5)
				(thermal_bridge_width 0.5)
				(island_removal_mode 0)
			)
			(polygon
				(pts
					(xy 400.79168 -48.23968) (xy 400.79168 -48.74768) (xy 400.41068 -48.74768) (xy 400.41068 -48.23968)
				)
			)
		)
	)
	(footprint ""
		(layer "B.Cu")
		(at 374.646952 -43.224958)
		(property "Reference" "R2T27"
			(at 0 0 0)
			(layer "B.SilkS")
			(hide yes)
			(effects
				(font
					(size 1.27 1.27)
				)
				(justify mirror)
			)
		)
		(property "Value" ""
			(at 0 0 0)
			(layer "B.Fab")
			(effects
				(font
					(size 1.27 1.27)
				)
				(justify mirror)
			)
		)
		(duplicate_pad_numbers_are_jumpers no)
		(fp_poly
			(pts
				(xy 0.2794 -0.1016) (xy -0.2794 -0.1016) (xy -0.2794 0.9906) (xy 0.2794 0.9906)
			)
			(stroke
				(width 0)
				(type default)
			)
			(fill no)
			(layer "B.CrtYd")
		)
		(fp_line
			(start -0.2794 -0.1016)
			(end 0.2794 -0.1016)
			(stroke
				(width 0.1)
				(type default)
			)
			(layer "B.Fab")
		)
		(fp_line
			(start -0.2794 0.9906)
			(end -0.2794 -0.1016)
			(stroke
				(width 0.1)
				(type default)
			)
			(layer "B.Fab")
		)
		(fp_line
			(start 0.2794 -0.1016)
			(end 0.2794 0.9906)
			(stroke
				(width 0.1)
				(type default)
			)
			(layer "B.Fab")
		)
		(fp_line
			(start 0.2794 0.9906)
			(end -0.2794 0.9906)
			(stroke
				(width 0.1)
				(type default)
			)
			(layer "B.Fab")
		)
		(pad "1" smd rect
			(at 0 0 180)
			(size 0.508 0.508)
			(layers "B.Cu" "B.Mask" "B.Paste")
			(net "H_CPU1_ERR1_G_N")
		)
		(pad "2" smd rect
			(at 0 0.889 180)
			(size 0.508 0.508)
			(layers "B.Cu" "B.Mask" "B.Paste")
			(net "H_CPU_ERR1_GTL_R_N")
		)
		(zone
			(layer "B.Cu")
			(hatch none 0.5)
			(connect_pads
				(clearance 0)
			)
			(min_thickness 0.25)
			(keepout
				(tracks allowed)
				(vias not_allowed)
				(pads allowed)
				(copperpour not_allowed)
				(footprints allowed)
			)
			(placement
				(enabled no)
				(sheetname "")
			)
			(fill
				(thermal_gap 0.5)
				(thermal_bridge_width 0.5)
				(island_removal_mode 0)
			)
			(polygon
				(pts
					(xy 374.900952 -42.970958) (xy 374.392952 -42.970958) (xy 374.392952 -42.589958) (xy 374.900952 -42.589958)
				)
			)
		)
		(zone
			(layer "B.Cu")
			(hatch none 0.5)
			(connect_pads
				(clearance 0)
			)
			(min_thickness 0.25)
			(keepout
				(tracks not_allowed)
				(vias allowed)
				(pads allowed)
				(copperpour not_allowed)
				(footprints allowed)
			)
			(placement
				(enabled no)
				(sheetname "")
			)
			(fill
				(thermal_gap 0.5)
				(thermal_bridge_width 0.5)
				(island_removal_mode 0)
			)
			(polygon
				(pts
					(xy 374.900952 -42.589958) (xy 374.392952 -42.589958) (xy 374.392952 -42.970958) (xy 374.900952 -42.970958)
				)
			)
		)
	)
)
